# S9S_MB_2U (Grand Teton) — schematic netlist excerpt (pin names and nets, part order shuffled) for the footprints in the layout excerpt that follows; sources: Cadence DE-HDL packaged netlist, KiCad conversion of 03242023_DA0F0TMBIJ0_F0T_Motherboard_J_brd_V01_OCP.brd

R3487  Q_RES  10K 1% CHIP  pkg 0402LF  page 147 : A = P3V3_AUX ; B = GPU_PRSNT_N
C767  Q_CAP_DIFFBUS  DIFF BUS_0.22UF 6.3V 20% X6S  pkg C0201  page 176 : \1\ = P5E_CPU1_PE2_TX_C_DP<3> ; \2\ = P5E_CPU1_PE2_TX_DP<3>
PC1219  Q_CAP  1UF 16V 10% X6S  pkg C0402  page 262 : A = SW_P12V_AUX_P1V05_PCH_AUX_FLT ; B = GND

(kicad_pcb
	(version 20260206)
	(generator "pcbnew")
	(generator_version "10.0")
	(general
		(thickness 1.6)
		(legacy_teardrops no)
	)
	(paper "A4")
	(title_block
		(title "03242023_DA0F0TMBIJ0_F0T_Motherboard_J_brd_V01_OCP.brd")
		(comment 1 "Grand Teton / footprints 2374-2376 of 6105")
	)
	(layers
		(0 "F.Cu" signal "TOP")
		(4 "In1.Cu" signal "GND")
		(6 "In2.Cu" signal "IN1")
		(8 "In3.Cu" signal "GND1")
		(10 "In4.Cu" signal "IN2")
		(12 "In5.Cu" signal "GND2")
		(14 "In6.Cu" signal "IN3")
		(16 "In7.Cu" signal "GND3")
		(18 "In8.Cu" signal "VCC")
		(20 "In9.Cu" signal "VCC1")
		(22 "In10.Cu" signal "GND4")
		(24 "In11.Cu" signal "IN4")
		(26 "In12.Cu" signal "GND5")
		(28 "In13.Cu" signal "IN5")
		(30 "In14.Cu" signal "GND6")
		(32 "In15.Cu" signal "IN6")
		(34 "In16.Cu" signal "GND7")
		(2 "B.Cu" signal "BOTTOM")
		(9 "F.Adhes" user "F.Adhesive")
		(11 "B.Adhes" user "B.Adhesive")
		(13 "F.Paste" user "Package Geometry/Pastemask Top")
		(15 "B.Paste" user "Package Geometry/Pastemask Bottom")
		(5 "F.SilkS" user "Ref Des/Silkscreen Top")
		(7 "B.SilkS" user "Ref Des/Silkscreen Bottom")
		(1 "F.Mask" user "Board Geometry/Soldermask Top")
		(3 "B.Mask" user "Board Geometry/Soldermask Bottom")
		(17 "Dwgs.User" user "User.Drawings")
		(19 "Cmts.User" user "User.Comments")
		(21 "Eco1.User" user "User.Eco1")
		(23 "Eco2.User" user "User.Eco2")
		(25 "Edge.Cuts" user "Board Geometry/Outline")
		(27 "Margin" user)
		(31 "F.CrtYd" user "Package Geometry/Place Bound Top")
		(29 "B.CrtYd" user "Package Geometry/Place Bound Bottom")
		(35 "F.Fab" user "Ref Des/Assembly Top")
		(33 "B.Fab" user "Ref Des/Assembly Bottom")
	)
	(footprint ""
		(layer "F.Cu")
		(at 24.069802 -411.434534)
		(property "Reference" "R3487"
			(at 0 0 0)
			(layer "F.SilkS")
			(hide yes)
			(effects
				(font
					(size 1.27 1.27)
				)
			)
		)
		(property "Value" ""
			(at 0 0 0)
			(layer "F.Fab")
			(effects
				(font
					(size 1.27 1.27)
				)
			)
		)
		(duplicate_pad_numbers_are_jumpers no)
		(fp_line
			(start -0.7874 -0.4064)
			(end 0.7874 -0.4064)
			(stroke
				(width 0.1524)
				(type default)
			)
			(layer "F.SilkS")
		)
		(fp_line
			(start -0.7874 0.4064)
			(end -0.7874 -0.4064)
			(stroke
				(width 0.1524)
				(type default)
			)
			(layer "F.SilkS")
		)
		(fp_line
			(start 0.7874 -0.4064)
			(end 0.7874 0.4064)
			(stroke
				(width 0.1524)
				(type default)
			)
			(layer "F.SilkS")
		)
		(fp_line
			(start 0.7874 0.4064)
			(end -0.7874 0.4064)
			(stroke
				(width 0.1524)
				(type default)
			)
			(layer "F.SilkS")
		)
		(fp_line
			(start -0.67945 -0.305054)
			(end -0.12065 -0.305054)
			(stroke
				(width 0.1)
				(type default)
			)
			(layer "F.Fab")
		)
		(fp_line
			(start -0.67945 0.3048)
			(end -0.67945 -0.305054)
			(stroke
				(width 0.1)
				(type default)
			)
			(layer "F.Fab")
		)
		(fp_line
			(start -0.12065 -0.305054)
			(end -0.12065 -0.2794)
			(stroke
				(width 0.1)
				(type default)
			)
			(layer "F.Fab")
		)
		(fp_line
			(start -0.12065 -0.2794)
			(end 0.12065 -0.2794)
			(stroke
				(width 0.1)
				(type default)
			)
			(layer "F.Fab")
		)
		(fp_line
			(start -0.12065 0.2794)
			(end -0.12065 0.3048)
			(stroke
				(width 0.1)
				(type default)
			)
			(layer "F.Fab")
		)
		(fp_line
			(start -0.12065 0.3048)
			(end -0.67945 0.3048)
			(stroke
				(width 0.1)
				(type default)
			)
			(layer "F.Fab")
		)
		(fp_line
			(start 0.120396 0.2794)
			(end -0.12065 0.2794)
			(stroke
				(width 0.1)
				(type default)
			)
			(layer "F.Fab")
		)
		(fp_line
			(start 0.120396 0.3048)
			(end 0.120396 0.2794)
			(stroke
				(width 0.1)
				(type default)
			)
			(layer "F.Fab")
		)
		(fp_line
			(start 0.12065 -0.3048)
			(end 0.67945 -0.3048)
			(stroke
				(width 0.1)
				(type default)
			)
			(layer "F.Fab")
		)
		(fp_line
			(start 0.12065 -0.2794)
			(end 0.12065 -0.3048)
			(stroke
				(width 0.1)
				(type default)
			)
			(layer "F.Fab")
		)
		(fp_line
			(start 0.67945 -0.3048)
			(end 0.67945 0.3048)
			(stroke
				(width 0.1)
				(type default)
			)
			(layer "F.Fab")
		)
		(fp_line
			(start 0.67945 0.3048)
			(end 0.120396 0.3048)
			(stroke
				(width 0.1)
				(type default)
			)
			(layer "F.Fab")
		)
		(pad "1" smd circle
			(at -0.40005 0)
			(size 0 0)
			(layers "F.Cu" "F.Mask" "F.Paste")
			(net "P3V3_AUX")
		)
		(pad "2" smd circle
			(at 0.40005 0)
			(size 0 0)
			(layers "F.Cu" "F.Mask" "F.Paste")
			(net "GPU_PRSNT_N")
		)
	)
	(footprint ""
		(layer "F.Cu")
		(at 156.888434 -402.371052 -90)
		(property "Reference" "C767"
			(at 0 0 270)
			(layer "F.SilkS")
			(hide yes)
			(effects
				(font
					(size 1.27 1.27)
				)
			)
		)
		(property "Value" ""
			(at 0 0 270)
			(layer "F.Fab")
			(effects
				(font
					(size 1.27 1.27)
				)
			)
		)
		(duplicate_pad_numbers_are_jumpers no)
		(fp_line
			(start -0.299974 0.150114)
			(end -0.299974 -0.150114)
			(stroke
				(width 0.1)
				(type default)
			)
			(layer "F.Fab")
		)
		(fp_line
			(start 0.299974 0.150114)
			(end -0.299974 0.150114)
			(stroke
				(width 0.1)
				(type default)
			)
			(layer "F.Fab")
		)
		(fp_line
			(start -0.299974 -0.150114)
			(end 0.299974 -0.150114)
			(stroke
				(width 0.1)
				(type default)
			)
			(layer "F.Fab")
		)
		(fp_line
			(start 0.299974 -0.150114)
			(end 0.299974 0.150114)
			(stroke
				(width 0.1)
				(type default)
			)
			(layer "F.Fab")
		)
		(pad "1" smd rect
			(at -0.2667 0 270)
			(size 0.3048 0.381)
			(layers "F.Cu" "F.Mask" "F.Paste")
			(net "P5E_CPU1_PE2_TX_C_DP<3>")
		)
		(pad "2" smd rect
			(at 0.2667 0 270)
			(size 0.3048 0.381)
			(layers "F.Cu" "F.Mask" "F.Paste")
			(net "P5E_CPU1_PE2_TX_DP<3>")
		)
	)
	(footprint ""
		(layer "F.Cu")
		(at 265.029696 -72.262492 90)
		(property "Reference" "PC1219"
			(at 0 0 90)
			(layer "F.SilkS")
			(hide yes)
			(effects
				(font
					(size 1.27 1.27)
				)
			)
		)
		(property "Value" ""
			(at 0 0 90)
			(layer "F.Fab")
			(effects
				(font
					(size 1.27 1.27)
				)
			)
		)
		(duplicate_pad_numbers_are_jumpers no)
		(fp_line
			(start 0.7874 -0.4064)
			(end 0.7874 0.4064)
			(stroke
				(width 0.1524)
				(type default)
			)
			(layer "F.SilkS")
		)
		(fp_line
			(start -0.7874 -0.4064)
			(end 0.7874 -0.4064)
			(stroke
				(width 0.1524)
				(type default)
			)
			(layer "F.SilkS")
		)
		(fp_line
			(start 0.7874 0.4064)
			(end -0.7874 0.4064)
			(stroke
				(width 0.1524)
				(type default)
			)
			(layer "F.SilkS")
		)
		(fp_line
			(start -0.7874 0.4064)
			(end -0.7874 -0.4064)
			(stroke
				(width 0.1524)
				(type default)
			)
			(layer "F.SilkS")
		)
		(fp_line
			(start -0.12065 -0.305054)
			(end -0.12065 -0.2794)
			(stroke
				(width 0.1)
				(type default)
			)
			(layer "F.Fab")
		)
		(fp_line
			(start -0.67945 -0.305054)
			(end -0.12065 -0.305054)
			(stroke
				(width 0.1)
				(type default)
			)
			(layer "F.Fab")
		)
		(fp_line
			(start 0.67945 -0.3048)
			(end 0.67945 0.3048)
			(stroke
				(width 0.1)
				(type default)
			)
			(layer "F.Fab")
		)
		(fp_line
			(start 0.12065 -0.3048)
			(end 0.67945 -0.3048)
			(stroke
				(width 0.1)
				(type default)
			)
			(layer "F.Fab")
		)
		(fp_line
			(start 0.12065 -0.2794)
			(end 0.12065 -0.3048)
			(stroke
				(width 0.1)
				(type default)
			)
			(layer "F.Fab")
		)
		(fp_line
			(start -0.12065 -0.2794)
			(end 0.12065 -0.2794)
			(stroke
				(width 0.1)
				(type default)
			)
			(layer "F.Fab")
		)
		(fp_line
			(start 0.120396 0.2794)
			(end -0.12065 0.2794)
			(stroke
				(width 0.1)
				(type default)
			)
			(layer "F.Fab")
		)
		(fp_line
			(start -0.12065 0.2794)
			(end -0.12065 0.3048)
			(stroke
				(width 0.1)
				(type default)
			)
			(layer "F.Fab")
		)
		(fp_line
			(start 0.67945 0.3048)
			(end 0.120396 0.3048)
			(stroke
				(width 0.1)
				(type default)
			)
			(layer "F.Fab")
		)
		(fp_line
			(start 0.120396 0.3048)
			(end 0.120396 0.2794)
			(stroke
				(width 0.1)
				(type default)
			)
			(layer "F.Fab")
		)
		(fp_line
			(start -0.12065 0.3048)
			(end -0.67945 0.3048)
			(stroke
				(width 0.1)
				(type default)
			)
			(layer "F.Fab")
		)
		(fp_line
			(start -0.67945 0.3048)
			(end -0.67945 -0.305054)
			(stroke
				(width 0.1)
				(type default)
			)
			(layer "F.Fab")
		)
		(pad "1" smd circle
			(at -0.40005 0 90)
			(size 0 0)
			(layers "F.Cu" "F.Mask" "F.Paste")
			(net "SW_P12V_AUX_P1V05_PCH_AUX_FLT")
		)
		(pad "2" smd circle
			(at 0.40005 0 90)
			(size 0 0)
			(layers "F.Cu" "F.Mask" "F.Paste")
			(net "GND")
		)
	)
)
